(kicad_pcb
	(version 20241229)
	(generator "pcbnew")
	(generator_version "9.0")
	(general
		(thickness 1.6296)
		(legacy_teardrops no)
	)
	(paper "A3")
	(title_block
		(title "Thunderbolt to 10GbE adapter")
		(date "2026-04-21")
		(rev "1.1.0")
		(company "Antmicro Ltd")
		(comment 1 "www.antmicro.com")
		(comment 9 "footprints 333-337 of 703")
	)
	(layers
		(0 "F.Cu" signal)
		(4 "In1.Cu" signal)
		(6 "In2.Cu" signal)
		(8 "In3.Cu" signal)
		(10 "In4.Cu" signal)
		(12 "In5.Cu" signal)
		(14 "In6.Cu" signal)
		(2 "B.Cu" signal)
		(9 "F.Adhes" user "F.Adhesive")
		(11 "B.Adhes" user "B.Adhesive")
		(13 "F.Paste" user)
		(15 "B.Paste" user)
		(5 "F.SilkS" user "F.Silkscreen")
		(7 "B.SilkS" user "B.Silkscreen")
		(1 "F.Mask" user)
		(3 "B.Mask" user)
		(17 "Dwgs.User" user "User.Drawings")
		(19 "Cmts.User" user "User.Comments")
		(21 "Eco1.User" user "User.Eco1")
		(23 "Eco2.User" user "User.Eco2")
		(25 "Edge.Cuts" user)
		(27 "Margin" user)
		(31 "F.CrtYd" user "F.Courtyard")
		(29 "B.CrtYd" user "B.Courtyard")
		(35 "F.Fab" user)
		(33 "B.Fab" user)
	)
	(footprint "antmicro-footprints:C_0402_1005Metric"
		(layer "F.Cu")
		(at 135.85 131.1 90)
		(descr "Capacitor SMD 0402")
		(tags "capacitor SMD 0402")
		(property "Reference" "C96"
			(at -0.170996 7.15 90)
			(layer "F.SilkS")
			(effects
				(font
					(size 0.7 0.7)
					(thickness 0.15)
				)
				(justify left bottom)
			)
		)
		(property "Value" "C_100n_0402"
			(at -1.022927 2.155213 90)
			(layer "F.Fab")
			(effects
				(font
					(size 0.7 0.7)
					(thickness 0.15)
				)
				(justify left bottom)
			)
		)
		(property "Datasheet" "https://www.murata.com/products/productdetail?partno=GRM155R61H104KE14%23"
			(at 0 0 90)
			(layer "F.Fab")
			(hide yes)
			(effects
				(font
					(size 1.27 1.27)
					(thickness 0.15)
				)
			)
		)
		(property "Description" "SMD Multilayer Ceramic Capacitor, 0.1 µF, 50 V, 0402 [1005 Metric], ± 10%, X5R, GRM Series"
			(at 0 0 90)
			(layer "F.Fab")
			(hide yes)
			(effects
				(font
					(size 1.27 1.27)
					(thickness 0.15)
				)
			)
		)
		(property "MPN" "GRM155R61H104KE14D"
			(at 0 0 90)
			(unlocked yes)
			(layer "F.Fab")
			(hide yes)
			(effects
				(font
					(size 1 1)
					(thickness 0.15)
				)
			)
		)
		(property "Manufacturer" "Murata"
			(at 0 0 90)
			(unlocked yes)
			(layer "F.Fab")
			(hide yes)
			(effects
				(font
					(size 1 1)
					(thickness 0.15)
				)
			)
		)
		(property "License" "Apache-2.0"
			(at 0 0 90)
			(unlocked yes)
			(layer "F.Fab")
			(hide yes)
			(effects
				(font
					(size 1 1)
					(thickness 0.15)
				)
			)
		)
		(property "Val" "100n"
			(at 0 0 90)
			(unlocked yes)
			(layer "F.Fab")
			(hide yes)
			(effects
				(font
					(size 1 1)
					(thickness 0.15)
				)
			)
		)
		(property "Voltage" "50V"
			(at 0 0 90)
			(unlocked yes)
			(layer "F.Fab")
			(hide yes)
			(effects
				(font
					(size 1 1)
					(thickness 0.15)
				)
			)
		)
		(property "Dielectric" "X5R"
			(at 0 0 90)
			(unlocked yes)
			(layer "F.Fab")
			(hide yes)
			(effects
				(font
					(size 1 1)
					(thickness 0.15)
				)
			)
		)
		(property "Author" "Antmicro"
			(at 0 0 90)
			(unlocked yes)
			(layer "F.Fab")
			(hide yes)
			(effects
				(font
					(size 1 1)
					(thickness 0.15)
				)
			)
		)
		(sheetname "/TB Controller - Power/")
		(sheetfile "tb-power.kicad_sch")
		(attr smd)
		(fp_rect
			(start -0.925 -0.47)
			(end 0.925 0.47)
			(stroke
				(width 0.05)
				(type default)
			)
			(fill no)
			(layer "F.CrtYd")
		)
		(fp_line
			(start 0.504 -0.25)
			(end 0.504 0.248)
			(stroke
				(width 0.15)
				(type solid)
			)
			(layer "F.Fab")
		)
		(fp_line
			(start -0.494 -0.25)
			(end 0.504 -0.25)
			(stroke
				(width 0.15)
				(type solid)
			)
			(layer "F.Fab")
		)
		(fp_line
			(start 0.504 0.248)
			(end -0.494 0.248)
			(stroke
				(width 0.15)
				(type solid)
			)
			(layer "F.Fab")
		)
		(fp_line
			(start -0.494 0.248)
			(end -0.494 -0.25)
			(stroke
				(width 0.15)
				(type solid)
			)
			(layer "F.Fab")
		)
		(fp_text user "Author: Antmicro"
			(at -0.939 3.399 90)
			(layer "F.Fab")
			(effects
				(font
					(size 0.7 0.7)
					(thickness 0.15)
				)
				(justify left bottom)
			)
		)
		(fp_text user "License: Apache-2.0"
			(at -0.939 5.799 90)
			(layer "F.Fab")
			(effects
				(font
					(size 0.7 0.7)
					(thickness 0.15)
				)
				(justify left bottom)
			)
		)
		(fp_text user "${REFERENCE}"
			(at -0.939 4.599 90)
			(layer "F.Fab")
			(effects
				(font
					(size 0.7 0.7)
					(thickness 0.15)
				)
				(justify left bottom)
			)
		)
		(pad "1" smd roundrect
			(at -0.48 0 90)
			(size 0.59 0.64)
			(layers "F.Cu" "F.Mask" "F.Paste")
			(roundrect_rratio 0.25)
			(net 23 "GND")
			(pintype "passive")
		)
		(pad "2" smd roundrect
			(at 0.48 0 90)
			(size 0.59 0.64)
			(layers "F.Cu" "F.Mask" "F.Paste")
			(roundrect_rratio 0.25)
			(net 57 "+3V3_TB")
			(pintype "passive")
		)
	)
	(footprint "antmicro-footprints:R_0402_1005Metric"
		(layer "F.Cu")
		(at 159.25 108.15 180)
		(descr "Resistor SMD 0402")
		(tags "resistor SMD 0402")
		(property "Reference" "R90"
			(at -12.950004 -17.25 180)
			(layer "F.SilkS")
			(effects
				(font
					(size 0.7 0.7)
					(thickness 0.15)
				)
			)
		)
		(property "Value" "R_100k_0402"
			(at -1.011843 1.772047 180)
			(layer "F.Fab")
			(effects
				(font
					(size 0.7 0.7)
					(thickness 0.15)
				)
				(justify left bottom)
			)
		)
		(property "Datasheet" "https://www.bourns.com/docs/product-datasheets/cr.pdf"
			(at 0 0 180)
			(layer "F.Fab")
			(hide yes)
			(effects
				(font
					(size 1.27 1.27)
					(thickness 0.15)
				)
			)
		)
		(property "Description" "SMD Chip Resistor, 100 kohm, ± 1%, 62.5 mW, 0402 [1005 Metric], Thick Film, General Purpose"
			(at 0 0 180)
			(layer "F.Fab")
			(hide yes)
			(effects
				(font
					(size 1.27 1.27)
					(thickness 0.15)
				)
			)
		)
		(property "MPN" "CR0402-FX-1003GLF"
			(at 0 0 180)
			(unlocked yes)
			(layer "F.Fab")
			(hide yes)
			(effects
				(font
					(size 1 1)
					(thickness 0.15)
				)
			)
		)
		(property "Manufacturer" "Bourns"
			(at 0 0 180)
			(unlocked yes)
			(layer "F.Fab")
			(hide yes)
			(effects
				(font
					(size 1 1)
					(thickness 0.15)
				)
			)
		)
		(property "License" "Apache-2.0"
			(at 0 0 180)
			(unlocked yes)
			(layer "F.Fab")
			(hide yes)
			(effects
				(font
					(size 1 1)
					(thickness 0.15)
				)
			)
		)
		(property "Author" "Antmicro"
			(at 0 0 180)
			(unlocked yes)
			(layer "F.Fab")
			(hide yes)
			(effects
				(font
					(size 1 1)
					(thickness 0.15)
				)
			)
		)
		(property "Val" "100k"
			(at 0 0 180)
			(unlocked yes)
			(layer "F.Fab")
			(hide yes)
			(effects
				(font
					(size 1 1)
					(thickness 0.15)
				)
			)
		)
		(property "Tolerance" "1%"
			(at 0 0 180)
			(unlocked yes)
			(layer "F.Fab")
			(hide yes)
			(effects
				(font
					(size 1 1)
					(thickness 0.15)
				)
			)
		)
		(sheetname "/X710 DCDC converters/")
		(sheetfile "DCDC_converters_X710.kicad_sch")
		(attr smd)
		(fp_rect
			(start -0.925 -0.47)
			(end 0.925 0.47)
			(stroke
				(width 0.05)
				(type default)
			)
			(fill no)
			(layer "F.CrtYd")
		)
		(fp_rect
			(start -0.5 -0.25)
			(end 0.5 0.25)
			(stroke
				(width 0.15)
				(type solid)
			)
			(fill no)
			(layer "F.Fab")
		)
		(fp_text user "${REFERENCE}"
			(at -0.95 3.168 180)
			(layer "F.Fab")
			(effects
				(font
					(size 0.7 0.7)
					(thickness 0.15)
				)
				(justify left bottom)
			)
		)
		(fp_text user "License: Apache-2.0"
			(at -0.95 5.169 180)
			(layer "F.Fab")
			(effects
				(font
					(size 0.7 0.7)
					(thickness 0.15)
				)
				(justify left bottom)
			)
		)
		(fp_text user "Author: Antmicro"
			(at -0.95 4.169 180)
			(layer "F.Fab")
			(effects
				(font
					(size 0.7 0.7)
					(thickness 0.15)
				)
				(justify left bottom)
			)
		)
		(pad "1" smd roundrect
			(at -0.48 0 180)
			(size 0.59 0.64)
			(layers "F.Cu" "F.Mask" "F.Paste")
			(roundrect_rratio 0.25)
			(net 381 "/X710 DCDC converters/1V0_PG")
			(pintype "passive")
		)
		(pad "2" smd roundrect
			(at 0.48 0 180)
			(size 0.59 0.64)
			(layers "F.Cu" "F.Mask" "F.Paste")
			(roundrect_rratio 0.25)
			(net 109 "/X710 DCDC converters/1V0_VCC")
			(pintype "passive")
		)
	)
	(footprint "antmicro-footprints:L_Bourns-SRP4021HMT"
		(layer "F.Cu")
		(at 147.149999 106.000001 -90)
		(property "Reference" "L8"
			(at 17.549996 -14.850002 270)
			(layer "F.SilkS")
			(effects
				(font
					(size 0.7 0.7)
					(thickness 0.15)
				)
			)
		)
		(property "Value" "L_1u_10A_Bourns-SRP4021HMT"
			(at -2.85 3.4 270)
			(layer "F.Fab")
			(effects
				(font
					(size 0.7 0.7)
					(thickness 0.15)
				)
				(justify left bottom)
			)
		)
		(property "Datasheet" "https://www.mouser.com/datasheet/2/54/Bourns_04_01_2025_SRP4021HMT_Datasheet-3580094.pdf"
			(at 0 0 270)
			(layer "F.Fab")
			(effects
				(font
					(size 0.7 0.7)
					(thickness 0.15)
				)
				(justify left bottom)
			)
		)
		(property "Description" "Power Inductors - SMD Ind,4.1x4.2x1.9mm,1uH+/-20%,10A, Shielded"
			(at 0 0 270)
			(layer "F.Fab")
			(effects
				(font
					(size 0.7 0.7)
					(thickness 0.15)
				)
				(justify left bottom)
			)
		)
		(property "Val" "1u/10A"
			(at 0 0 270)
			(unlocked yes)
			(layer "F.Fab")
			(hide yes)
			(effects
				(font
					(size 1 1)
					(thickness 0.15)
				)
			)
		)
		(property "Manufacturer" "Bourns"
			(at 0 0 270)
			(unlocked yes)
			(layer "F.Fab")
			(hide yes)
			(effects
				(font
					(size 1 1)
					(thickness 0.15)
				)
			)
		)
		(property "MPN" "SRP4021HMT-1R0M"
			(at 0 0 270)
			(unlocked yes)
			(layer "F.Fab")
			(hide yes)
			(effects
				(font
					(size 1 1)
					(thickness 0.15)
				)
			)
		)
		(property "ISat" ""
			(at 0 0 270)
			(unlocked yes)
			(layer "F.Fab")
			(hide yes)
			(effects
				(font
					(size 1 1)
					(thickness 0.15)
				)
			)
		)
		(property "Isat" "8A"
			(at 0 0 270)
			(unlocked yes)
			(layer "F.Fab")
			(hide yes)
			(effects
				(font
					(size 1 1)
					(thickness 0.15)
				)
			)
		)
		(property "IMax" ""
			(at 0 0 270)
			(unlocked yes)
			(layer "F.Fab")
			(hide yes)
			(effects
				(font
					(size 1 1)
					(thickness 0.15)
				)
			)
		)
		(property "Imax" "10A"
			(at 0 0 270)
			(unlocked yes)
			(layer "F.Fab")
			(hide yes)
			(effects
				(font
					(size 1 1)
					(thickness 0.15)
				)
			)
		)
		(property "Size" "4.2x4.1"
			(at 0 0 270)
			(unlocked yes)
			(layer "F.Fab")
			(hide yes)
			(effects
				(font
					(size 1 1)
					(thickness 0.15)
				)
			)
		)
		(property "Author" "Antmicro"
			(at 0 0 270)
			(unlocked yes)
			(layer "F.Fab")
			(hide yes)
			(effects
				(font
					(size 1 1)
					(thickness 0.15)
				)
			)
		)
		(property "License" "Apache-2.0"
			(at 0 0 270)
			(unlocked yes)
			(layer "F.Fab")
			(hide yes)
			(effects
				(font
					(size 1 1)
					(thickness 0.15)
				)
			)
		)
		(sheetname "/X710 DCDC converters/")
		(sheetfile "DCDC_converters_X710.kicad_sch")
		(attr smd)
		(fp_line
			(start -0.8 2.05)
			(end 0.8 2.05)
			(stroke
				(width 0.15)
				(type solid)
			)
			(layer "F.SilkS")
		)
		(fp_line
			(start -0.8 -2.05)
			(end 0.8 -2.05)
			(stroke
				(width 0.15)
				(type solid)
			)
			(layer "F.SilkS")
		)
		(fp_rect
			(start -2.85 -2.3)
			(end 2.85 2.3)
			(stroke
				(width 0.05)
				(type solid)
			)
			(fill no)
			(layer "F.CrtYd")
		)
		(fp_rect
			(start -2 -2.05)
			(end 2 2.05)
			(stroke
				(width 0.15)
				(type solid)
			)
			(fill no)
			(layer "F.Fab")
		)
		(fp_text user "License: Apache-2.0"
			(at -2.85 7 270)
			(layer "F.Fab")
			(effects
				(font
					(size 0.7 0.7)
					(thickness 0.15)
				)
				(justify left bottom)
			)
		)
		(fp_text user "${REFERENCE}"
			(at -2.85 5.8 270)
			(layer "F.Fab")
			(effects
				(font
					(size 0.7 0.7)
					(thickness 0.15)
				)
				(justify left bottom)
			)
		)
		(fp_text user "Author: Antmicro"
			(at -2.85 4.6 270)
			(layer "F.Fab")
			(effects
				(font
					(size 0.7 0.7)
					(thickness 0.15)
				)
				(justify left bottom)
			)
		)
		(pad "1" smd rect
			(at 1.85 0 90)
			(size 1.5 3.5)
			(layers "F.Cu" "F.Mask" "F.Paste")
			(net 313 "/X710 DCDC converters/DVDD_SW")
			(pintype "passive")
		)
		(pad "2" smd rect
			(at -1.85 0 90)
			(size 1.5 3.5)
			(layers "F.Cu" "F.Mask" "F.Paste")
			(net 341 "/X710 DCDC converters/+DVDD_OUT")
			(pintype "passive")
		)
	)
	(footprint "antmicro-footprints:R_0402_1005Metric"
		(layer "F.Cu")
		(at 158.104998 67.124999 -90)
		(descr "Resistor SMD 0402")
		(tags "resistor SMD 0402")
		(property "Reference" "R191"
			(at -12.324999 -20.295 270)
			(layer "F.SilkS")
			(effects
				(font
					(size 0.7 0.7)
					(thickness 0.15)
				)
			)
		)
		(property "Value" "R_150R_0402"
			(at -1.011843 1.772047 270)
			(layer "F.Fab")
			(effects
				(font
					(size 0.7 0.7)
					(thickness 0.15)
				)
				(justify left bottom)
			)
		)
		(property "Datasheet" "https://www.bourns.com/docs/product-datasheets/cr.pdf"
			(at 0 0 270)
			(layer "F.Fab")
			(hide yes)
			(effects
				(font
					(size 1.27 1.27)
					(thickness 0.15)
				)
			)
		)
		(property "Description" "SMD Chip Resistor, 150 ohm, ± 1%, 62.5 mW, 0402 [1005 Metric], Thick Film, General Purpose"
			(at 0 0 270)
			(layer "F.Fab")
			(hide yes)
			(effects
				(font
					(size 1.27 1.27)
					(thickness 0.15)
				)
			)
		)
		(property "MPN" "CR0402-FX-1500GLF"
			(at 0 0 270)
			(unlocked yes)
			(layer "F.Fab")
			(hide yes)
			(effects
				(font
					(size 1 1)
					(thickness 0.15)
				)
			)
		)
		(property "Manufacturer" "Bourns"
			(at 0 0 270)
			(unlocked yes)
			(layer "F.Fab")
			(hide yes)
			(effects
				(font
					(size 1 1)
					(thickness 0.15)
				)
			)
		)
		(property "License" "Apache-2.0"
			(at 0 0 270)
			(unlocked yes)
			(layer "F.Fab")
			(hide yes)
			(effects
				(font
					(size 1 1)
					(thickness 0.15)
				)
			)
		)
		(property "Author" "Antmicro"
			(at 0 0 270)
			(unlocked yes)
			(layer "F.Fab")
			(hide yes)
			(effects
				(font
					(size 1 1)
					(thickness 0.15)
				)
			)
		)
		(property "Val" "150R"
			(at 0 0 270)
			(unlocked yes)
			(layer "F.Fab")
			(hide yes)
			(effects
				(font
					(size 1 1)
					(thickness 0.15)
				)
			)
		)
		(property "Tolerance" "1%"
			(at 0 0 270)
			(unlocked yes)
			(layer "F.Fab")
			(hide yes)
			(effects
				(font
					(size 1 1)
					(thickness 0.15)
				)
			)
		)
		(sheetname "/X710-AT2 10GbE/")
		(sheetfile "x710-at2-10gbe.kicad_sch")
		(attr smd)
		(fp_rect
			(start -0.925 -0.47)
			(end 0.925 0.47)
			(stroke
				(width 0.05)
				(type default)
			)
			(fill no)
			(layer "F.CrtYd")
		)
		(fp_rect
			(start -0.5 -0.25)
			(end 0.5 0.25)
			(stroke
				(width 0.15)
				(type solid)
			)
			(fill no)
			(layer "F.Fab")
		)
		(fp_text user "Author: Antmicro"
			(at -0.95 4.169 270)
			(layer "F.Fab")
			(effects
				(font
					(size 0.7 0.7)
					(thickness 0.15)
				)
				(justify left bottom)
			)
		)
		(fp_text user "License: Apache-2.0"
			(at -0.95 5.169 270)
			(layer "F.Fab")
			(effects
				(font
					(size 0.7 0.7)
					(thickness 0.15)
				)
				(justify left bottom)
			)
		)
		(fp_text user "${REFERENCE}"
			(at -0.95 3.168 270)
			(layer "F.Fab")
			(effects
				(font
					(size 0.7 0.7)
					(thickness 0.15)
				)
				(justify left bottom)
			)
		)
		(pad "1" smd roundrect
			(at -0.48 0 270)
			(size 0.59 0.64)
			(layers "F.Cu" "F.Mask" "F.Paste")
			(roundrect_rratio 0.25)
			(net 23 "GND")
			(pintype "passive")
		)
		(pad "2" smd roundrect
			(at 0.48 0 270)
			(size 0.59 0.64)
			(layers "F.Cu" "F.Mask" "F.Paste")
			(roundrect_rratio 0.25)
			(net 25 "/X710-AT2 10GbE/25MHZ_OSC_AC.+")
			(pintype "passive")
		)
	)
	(footprint "antmicro-footprints:C_0603_1608Metric_EIA"
		(layer "F.Cu")
		(at 143.054999 99.774999 -90)
		(descr "Capacitor SMD 0603, IPC-7351 Density Level A")
		(tags "Capacitor 0603")
		(property "Reference" "C166"
			(at -9.249998 -35.195001 270)
			(layer "F.SilkS")
			(effects
				(font
					(size 0.7 0.7)
					(thickness 0.15)
				)
			)
		)
		(property "Value" "C_22u_16V_0603"
			(at -1.42757 1.770288 270)
			(layer "F.Fab")
			(effects
				(font
					(size 0.7 0.7)
					(thickness 0.15)
				)
				(justify left bottom)
			)
		)
		(property "Datasheet" "https://product.samsungsem.com/mlcc/CL10A226MO7JZN.do"
			(at 0 0 270)
			(layer "F.Fab")
			(hide yes)
			(effects
				(font
					(size 1.27 1.27)
					(thickness 0.15)
				)
			)
		)
		(property "Description" "SMD Multilayer Ceramic Capacitor"
			(at 0 0 270)
			(layer "F.Fab")
			(hide yes)
			(effects
				(font
					(size 1.27 1.27)
					(thickness 0.15)
				)
			)
		)
		(property "MPN" "CL10A226MO7JZNC"
			(at 0 0 270)
			(unlocked yes)
			(layer "F.Fab")
			(hide yes)
			(effects
				(font
					(size 1 1)
					(thickness 0.15)
				)
			)
		)
		(property "Manufacturer" "Samsung Electro-Mechanics"
			(at 0 0 270)
			(unlocked yes)
			(layer "F.Fab")
			(hide yes)
			(effects
				(font
					(size 1 1)
					(thickness 0.15)
				)
			)
		)
		(property "License" "Apache-2.0"
			(at 0 0 270)
			(unlocked yes)
			(layer "F.Fab")
			(hide yes)
			(effects
				(font
					(size 1 1)
					(thickness 0.15)
				)
			)
		)
		(property "Author" "Antmicro"
			(at 0 0 270)
			(unlocked yes)
			(layer "F.Fab")
			(hide yes)
			(effects
				(font
					(size 1 1)
					(thickness 0.15)
				)
			)
		)
		(property "Val" "22u"
			(at 0 0 270)
			(unlocked yes)
			(layer "F.Fab")
			(hide yes)
			(effects
				(font
					(size 1 1)
					(thickness 0.15)
				)
			)
		)
		(property "Voltage" "16V"
			(at 0 0 270)
			(unlocked yes)
			(layer "F.Fab")
			(hide yes)
			(effects
				(font
					(size 1 1)
					(thickness 0.15)
				)
			)
		)
		(property "Dielectric" ""
			(at 0 0 270)
			(unlocked yes)
			(layer "F.Fab")
			(hide yes)
			(effects
				(font
					(size 1 1)
					(thickness 0.15)
				)
			)
		)
		(sheetname "/X710-AT2 power/")
		(sheetfile "x710-at2-power.kicad_sch")
		(attr smd)
		(fp_line
			(start -0.15 0.55)
			(end 0.15 0.55)
			(stroke
				(width 0.15)
				(type solid)
			)
			(layer "F.SilkS")
		)
		(fp_line
			(start -0.15 -0.55)
			(end 0.15 -0.55)
			(stroke
				(width 0.15)
				(type solid)
			)
			(layer "F.SilkS")
		)
		(fp_rect
			(start -1.25 -0.65)
			(end 1.25 0.65)
			(stroke
				(width 0.05)
				(type solid)
			)
			(fill no)
			(layer "F.CrtYd")
		)
		(fp_rect
			(start -0.8 -0.45)
			(end 0.8 0.45)
			(stroke
				(width 0.15)
				(type solid)
			)
			(fill no)
			(layer "F.Fab")
		)
		(fp_text user "License: Apache-2.0"
			(at -1.682 5.895 270)
			(layer "F.Fab")
			(effects
				(font
					(size 0.7 0.7)
					(thickness 0.15)
				)
				(justify left bottom)
			)
		)
		(fp_text user "${REFERENCE}"
			(at -1.682 3.895 270)
			(layer "F.Fab")
			(effects
				(font
					(size 0.7 0.7)
					(thickness 0.15)
				)
				(justify left bottom)
			)
		)
		(fp_text user "Author: Antmicro"
			(at -1.682 4.894 270)
			(layer "F.Fab")
			(effects
				(font
					(size 0.7 0.7)
					(thickness 0.15)
				)
				(justify left bottom)
			)
		)
		(pad "1" smd roundrect
			(at -0.7 0 270)
			(size 0.8 1.1)
			(layers "F.Cu" "F.Mask" "F.Paste")
			(roundrect_rratio 0.2)
			(net 23 "GND")
			(pintype "passive")
		)
		(pad "2" smd roundrect
			(at 0.7 0 270)
			(size 0.8 1.1)
			(layers "F.Cu" "F.Mask" "F.Paste")
			(roundrect_rratio 0.2)
			(net 6 "DVDD")
			(pintype "passive")
		)
	)
)
